(kicad_pcb
	(version 20260206)
	(generator "pcbnew")
	(generator_version "10.0")
	(general
		(thickness 1.6)
		(legacy_teardrops no)
	)
	(paper "A4")
	(title_block
		(title "04192023_DAF0TMB3IC0_F0TG_MB_C_brd_V02_OCP.brd")
		(comment 1 "Grand Teton / footprints 7775-7783 of 8354")
	)
	(layers
		(0 "F.Cu" signal "TOP")
		(4 "In1.Cu" signal "GND")
		(6 "In2.Cu" signal "IN1")
		(8 "In3.Cu" signal "GND1")
		(10 "In4.Cu" signal "IN2")
		(12 "In5.Cu" signal "GND2")
		(14 "In6.Cu" signal "IN3")
		(16 "In7.Cu" signal "GND3")
		(18 "In8.Cu" signal "VCC")
		(20 "In9.Cu" signal "VCC1")
		(22 "In10.Cu" signal "GND4")
		(24 "In11.Cu" signal "IN4")
		(26 "In12.Cu" signal "GND5")
		(28 "In13.Cu" signal "IN5")
		(30 "In14.Cu" signal "GND6")
		(32 "In15.Cu" signal "IN6")
		(34 "In16.Cu" signal "GND7")
		(2 "B.Cu" signal "BOTTOM")
		(9 "F.Adhes" user "F.Adhesive")
		(11 "B.Adhes" user "B.Adhesive")
		(13 "F.Paste" user "Package Geometry/Pastemask Top")
		(15 "B.Paste" user "Package Geometry/Pastemask Bottom")
		(5 "F.SilkS" user "Ref Des/Silkscreen Top")
		(7 "B.SilkS" user "Ref Des/Silkscreen Bottom")
		(1 "F.Mask" user "Board Geometry/Soldermask Top")
		(3 "B.Mask" user "Board Geometry/Soldermask Bottom")
		(17 "Dwgs.User" user "User.Drawings")
		(19 "Cmts.User" user "User.Comments")
		(21 "Eco1.User" user "User.Eco1")
		(23 "Eco2.User" user "User.Eco2")
		(25 "Edge.Cuts" user "Board Geometry/Outline")
		(27 "Margin" user)
		(31 "F.CrtYd" user "Package Geometry/Place Bound Top")
		(29 "B.CrtYd" user "Package Geometry/Place Bound Bottom")
		(35 "F.Fab" user "Ref Des/Assembly Top")
		(33 "B.Fab" user "Ref Des/Assembly Bottom")
	)
	(footprint ""
		(layer "B.Cu")
		(at 399.034508 -330.090272)
		(property "Reference" "R474"
			(at 0 0 0)
			(layer "B.SilkS")
			(hide yes)
			(effects
				(font
					(size 1.27 1.27)
				)
				(justify mirror)
			)
		)
		(property "Value" ""
			(at 0 0 0)
			(layer "B.Fab")
			(effects
				(font
					(size 1.27 1.27)
				)
				(justify mirror)
			)
		)
		(duplicate_pad_numbers_are_jumpers no)
		(fp_line
			(start -0.7874 -0.4064)
			(end -0.7874 0.4064)
			(stroke
				(width 0.1524)
				(type default)
			)
			(layer "B.SilkS")
		)
		(fp_line
			(start -0.7874 0.4064)
			(end 0.7874 0.4064)
			(stroke
				(width 0.1524)
				(type default)
			)
			(layer "B.SilkS")
		)
		(fp_line
			(start 0.7874 -0.4064)
			(end -0.7874 -0.4064)
			(stroke
				(width 0.1524)
				(type default)
			)
			(layer "B.SilkS")
		)
		(fp_line
			(start 0.7874 0.4064)
			(end 0.7874 -0.4064)
			(stroke
				(width 0.1524)
				(type default)
			)
			(layer "B.SilkS")
		)
		(fp_line
			(start -0.67945 -0.3048)
			(end -0.67945 0.3048)
			(stroke
				(width 0.1)
				(type default)
			)
			(layer "B.Fab")
		)
		(fp_line
			(start -0.67945 0.3048)
			(end -0.120396 0.3048)
			(stroke
				(width 0.1)
				(type default)
			)
			(layer "B.Fab")
		)
		(fp_line
			(start -0.12065 -0.3048)
			(end -0.67945 -0.3048)
			(stroke
				(width 0.1)
				(type default)
			)
			(layer "B.Fab")
		)
		(fp_line
			(start -0.12065 -0.2794)
			(end -0.12065 -0.3048)
			(stroke
				(width 0.1)
				(type default)
			)
			(layer "B.Fab")
		)
		(fp_line
			(start -0.120396 0.2794)
			(end 0.12065 0.2794)
			(stroke
				(width 0.1)
				(type default)
			)
			(layer "B.Fab")
		)
		(fp_line
			(start -0.120396 0.3048)
			(end -0.120396 0.2794)
			(stroke
				(width 0.1)
				(type default)
			)
			(layer "B.Fab")
		)
		(fp_line
			(start 0.12065 -0.305054)
			(end 0.12065 -0.2794)
			(stroke
				(width 0.1)
				(type default)
			)
			(layer "B.Fab")
		)
		(fp_line
			(start 0.12065 -0.2794)
			(end -0.12065 -0.2794)
			(stroke
				(width 0.1)
				(type default)
			)
			(layer "B.Fab")
		)
		(fp_line
			(start 0.12065 0.2794)
			(end 0.12065 0.3048)
			(stroke
				(width 0.1)
				(type default)
			)
			(layer "B.Fab")
		)
		(fp_line
			(start 0.12065 0.3048)
			(end 0.67945 0.3048)
			(stroke
				(width 0.1)
				(type default)
			)
			(layer "B.Fab")
		)
		(fp_line
			(start 0.67945 -0.305054)
			(end 0.12065 -0.305054)
			(stroke
				(width 0.1)
				(type default)
			)
			(layer "B.Fab")
		)
		(fp_line
			(start 0.67945 0.3048)
			(end 0.67945 -0.305054)
			(stroke
				(width 0.1)
				(type default)
			)
			(layer "B.Fab")
		)
		(pad "1" smd circle
			(at 0.40005 0 180)
			(size 0 0)
			(layers "B.Cu" "B.Mask" "B.Paste")
			(net "RST_ESPI_CPU0_RSTOUT_N")
		)
		(pad "2" smd circle
			(at -0.40005 0 180)
			(size 0 0)
			(layers "B.Cu" "B.Mask" "B.Paste")
			(net "RST_ESPI_CPU0_R_RSTOUT_N")
		)
	)
	(footprint ""
		(layer "B.Cu")
		(at 115.818412 -388.011162 -90)
		(property "Reference" "C457"
			(at 0 0 90)
			(layer "B.SilkS")
			(hide yes)
			(effects
				(font
					(size 1.27 1.27)
				)
				(justify mirror)
			)
		)
		(property "Value" ""
			(at 0 0 90)
			(layer "B.Fab")
			(effects
				(font
					(size 1.27 1.27)
				)
				(justify mirror)
			)
		)
		(duplicate_pad_numbers_are_jumpers no)
		(fp_line
			(start -0.299974 0.150114)
			(end 0.299974 0.150114)
			(stroke
				(width 0.1)
				(type default)
			)
			(layer "B.Fab")
		)
		(fp_line
			(start 0.299974 0.150114)
			(end 0.299974 -0.150114)
			(stroke
				(width 0.1)
				(type default)
			)
			(layer "B.Fab")
		)
		(fp_line
			(start -0.299974 -0.150114)
			(end -0.299974 0.150114)
			(stroke
				(width 0.1)
				(type default)
			)
			(layer "B.Fab")
		)
		(fp_line
			(start 0.299974 -0.150114)
			(end -0.299974 -0.150114)
			(stroke
				(width 0.1)
				(type default)
			)
			(layer "B.Fab")
		)
		(pad "1" smd rect
			(at 0.2667 0 90)
			(size 0.3048 0.381)
			(layers "B.Cu" "B.Mask" "B.Paste")
			(net "P0V9_CPU1_RT3_2A")
		)
		(pad "2" smd rect
			(at -0.2667 0 90)
			(size 0.3048 0.381)
			(layers "B.Cu" "B.Mask" "B.Paste")
			(net "GND")
		)
	)
	(footprint ""
		(layer "B.Cu")
		(at 321.595496 -335.063084 90)
		(property "Reference" "PC124_3"
			(at 0 0 90)
			(layer "B.SilkS")
			(hide yes)
			(effects
				(font
					(size 1.27 1.27)
				)
				(justify mirror)
			)
		)
		(property "Value" ""
			(at 0 0 90)
			(layer "B.Fab")
			(effects
				(font
					(size 1.27 1.27)
				)
				(justify mirror)
			)
		)
		(duplicate_pad_numbers_are_jumpers no)
		(fp_line
			(start 1.524 -0.762)
			(end -1.524 -0.762)
			(stroke
				(width 0.1524)
				(type default)
			)
			(layer "B.SilkS")
		)
		(fp_line
			(start -1.524 -0.762)
			(end -1.524 0.762)
			(stroke
				(width 0.1524)
				(type default)
			)
			(layer "B.SilkS")
		)
		(fp_line
			(start 1.524 0.762)
			(end 1.524 -0.762)
			(stroke
				(width 0.1524)
				(type default)
			)
			(layer "B.SilkS")
		)
		(fp_line
			(start -1.524 0.762)
			(end 1.524 0.762)
			(stroke
				(width 0.1524)
				(type default)
			)
			(layer "B.SilkS")
		)
		(fp_line
			(start 1.1049 -0.724916)
			(end 1.1049 0.724916)
			(stroke
				(width 0.1)
				(type default)
			)
			(layer "B.Fab")
		)
		(fp_line
			(start -1.1049 -0.724916)
			(end 1.1049 -0.724916)
			(stroke
				(width 0.1)
				(type default)
			)
			(layer "B.Fab")
		)
		(fp_line
			(start 1.1049 0.724916)
			(end -1.1049 0.724916)
			(stroke
				(width 0.1)
				(type default)
			)
			(layer "B.Fab")
		)
		(fp_line
			(start -1.1049 0.724916)
			(end -1.1049 -0.724916)
			(stroke
				(width 0.1)
				(type default)
			)
			(layer "B.Fab")
		)
		(pad "1" smd rect
			(at 0.889 0 90)
			(size 1.016 1.27)
			(layers "B.Cu" "B.Mask" "B.Paste")
			(net "SW_P12V_AUX_PVDDCR_CPU1_P0_FLT")
		)
		(pad "2" smd rect
			(at -0.889 0 90)
			(size 1.016 1.27)
			(layers "B.Cu" "B.Mask" "B.Paste")
			(net "GND")
		)
	)
	(footprint ""
		(layer "B.Cu")
		(at 370.905278 -145.536158)
		(property "Reference" "C302"
			(at 0 0 0)
			(layer "B.SilkS")
			(hide yes)
			(effects
				(font
					(size 1.27 1.27)
				)
				(justify mirror)
			)
		)
		(property "Value" ""
			(at 0 0 0)
			(layer "B.Fab")
			(effects
				(font
					(size 1.27 1.27)
				)
				(justify mirror)
			)
		)
		(duplicate_pad_numbers_are_jumpers no)
		(fp_line
			(start -0.7874 -0.4064)
			(end -0.7874 0.4064)
			(stroke
				(width 0.1524)
				(type default)
			)
			(layer "B.SilkS")
		)
		(fp_line
			(start -0.7874 0.4064)
			(end 0.7874 0.4064)
			(stroke
				(width 0.1524)
				(type default)
			)
			(layer "B.SilkS")
		)
		(fp_line
			(start 0.7874 -0.4064)
			(end -0.7874 -0.4064)
			(stroke
				(width 0.1524)
				(type default)
			)
			(layer "B.SilkS")
		)
		(fp_line
			(start 0.7874 0.4064)
			(end 0.7874 -0.4064)
			(stroke
				(width 0.1524)
				(type default)
			)
			(layer "B.SilkS")
		)
		(fp_line
			(start -0.67945 -0.3048)
			(end -0.67945 0.3048)
			(stroke
				(width 0.1)
				(type default)
			)
			(layer "B.Fab")
		)
		(fp_line
			(start -0.67945 0.3048)
			(end -0.120396 0.3048)
			(stroke
				(width 0.1)
				(type default)
			)
			(layer "B.Fab")
		)
		(fp_line
			(start -0.12065 -0.3048)
			(end -0.67945 -0.3048)
			(stroke
				(width 0.1)
				(type default)
			)
			(layer "B.Fab")
		)
		(fp_line
			(start -0.12065 -0.2794)
			(end -0.12065 -0.3048)
			(stroke
				(width 0.1)
				(type default)
			)
			(layer "B.Fab")
		)
		(fp_line
			(start -0.120396 0.2794)
			(end 0.12065 0.2794)
			(stroke
				(width 0.1)
				(type default)
			)
			(layer "B.Fab")
		)
		(fp_line
			(start -0.120396 0.3048)
			(end -0.120396 0.2794)
			(stroke
				(width 0.1)
				(type default)
			)
			(layer "B.Fab")
		)
		(fp_line
			(start 0.12065 -0.305054)
			(end 0.12065 -0.2794)
			(stroke
				(width 0.1)
				(type default)
			)
			(layer "B.Fab")
		)
		(fp_line
			(start 0.12065 -0.2794)
			(end -0.12065 -0.2794)
			(stroke
				(width 0.1)
				(type default)
			)
			(layer "B.Fab")
		)
		(fp_line
			(start 0.12065 0.2794)
			(end 0.12065 0.3048)
			(stroke
				(width 0.1)
				(type default)
			)
			(layer "B.Fab")
		)
		(fp_line
			(start 0.12065 0.3048)
			(end 0.67945 0.3048)
			(stroke
				(width 0.1)
				(type default)
			)
			(layer "B.Fab")
		)
		(fp_line
			(start 0.67945 -0.305054)
			(end 0.12065 -0.305054)
			(stroke
				(width 0.1)
				(type default)
			)
			(layer "B.Fab")
		)
		(fp_line
			(start 0.67945 0.3048)
			(end 0.67945 -0.305054)
			(stroke
				(width 0.1)
				(type default)
			)
			(layer "B.Fab")
		)
		(pad "1" smd circle
			(at 0.40005 0 180)
			(size 0 0)
			(layers "B.Cu" "B.Mask" "B.Paste")
			(net "SVID_PVDDCR_CPU0_P0_SVC_R")
		)
		(pad "2" smd circle
			(at -0.40005 0 180)
			(size 0 0)
			(layers "B.Cu" "B.Mask" "B.Paste")
			(net "GND")
		)
	)
	(footprint ""
		(layer "B.Cu")
		(at 82.306414 -386.766562 90)
		(property "Reference" "C337"
			(at 0 0 90)
			(layer "B.SilkS")
			(hide yes)
			(effects
				(font
					(size 1.27 1.27)
				)
				(justify mirror)
			)
		)
		(property "Value" ""
			(at 0 0 90)
			(layer "B.Fab")
			(effects
				(font
					(size 1.27 1.27)
				)
				(justify mirror)
			)
		)
		(duplicate_pad_numbers_are_jumpers no)
		(fp_line
			(start 0.299974 -0.150114)
			(end -0.299974 -0.150114)
			(stroke
				(width 0.1)
				(type default)
			)
			(layer "B.Fab")
		)
		(fp_line
			(start -0.299974 -0.150114)
			(end -0.299974 0.150114)
			(stroke
				(width 0.1)
				(type default)
			)
			(layer "B.Fab")
		)
		(fp_line
			(start 0.299974 0.150114)
			(end 0.299974 -0.150114)
			(stroke
				(width 0.1)
				(type default)
			)
			(layer "B.Fab")
		)
		(fp_line
			(start -0.299974 0.150114)
			(end 0.299974 0.150114)
			(stroke
				(width 0.1)
				(type default)
			)
			(layer "B.Fab")
		)
		(pad "1" smd rect
			(at 0.2667 0 270)
			(size 0.3048 0.381)
			(layers "B.Cu" "B.Mask" "B.Paste")
			(net "P0V9_CPU1_RT1_2A")
		)
		(pad "2" smd rect
			(at -0.2667 0 270)
			(size 0.3048 0.381)
			(layers "B.Cu" "B.Mask" "B.Paste")
			(net "GND")
		)
	)
	(footprint ""
		(layer "B.Cu")
		(at 365.09579 -393.96416 180)
		(property "Reference" "R1114"
			(at 0 0 0)
			(layer "B.SilkS")
			(hide yes)
			(effects
				(font
					(size 1.27 1.27)
				)
				(justify mirror)
			)
		)
		(property "Value" ""
			(at 0 0 0)
			(layer "B.Fab")
			(effects
				(font
					(size 1.27 1.27)
				)
				(justify mirror)
			)
		)
		(duplicate_pad_numbers_are_jumpers no)
		(fp_line
			(start 0.32512 0.175006)
			(end 0.32512 -0.175006)
			(stroke
				(width 0.1)
				(type default)
			)
			(layer "B.Fab")
		)
		(fp_line
			(start 0.32512 -0.175006)
			(end -0.32512 -0.175006)
			(stroke
				(width 0.1)
				(type default)
			)
			(layer "B.Fab")
		)
		(fp_line
			(start -0.32512 0.175006)
			(end 0.32512 0.175006)
			(stroke
				(width 0.1)
				(type default)
			)
			(layer "B.Fab")
		)
		(fp_line
			(start -0.32512 -0.175006)
			(end -0.32512 0.175006)
			(stroke
				(width 0.1)
				(type default)
			)
			(layer "B.Fab")
		)
		(pad "1" smd rect
			(at 0.2667 0)
			(size 0.3048 0.381)
			(layers "B.Cu" "B.Mask" "B.Paste")
			(net "P1V8_CPU0_RT_1D")
		)
		(pad "2" smd rect
			(at -0.2667 0 180)
			(size 0.3048 0.381)
			(layers "B.Cu" "B.Mask" "B.Paste")
			(net "TEST0_RT_CPU0_P3")
		)
	)
	(footprint ""
		(layer "B.Cu")
		(at 355.006656 -169.619676 -90)
		(property "Reference" "PC573_5"
			(at 0 0 90)
			(layer "B.SilkS")
			(hide yes)
			(effects
				(font
					(size 1.27 1.27)
				)
				(justify mirror)
			)
		)
		(property "Value" ""
			(at 0 0 90)
			(layer "B.Fab")
			(effects
				(font
					(size 1.27 1.27)
				)
				(justify mirror)
			)
		)
		(duplicate_pad_numbers_are_jumpers no)
		(fp_line
			(start -1.524 0.762)
			(end 1.524 0.762)
			(stroke
				(width 0.1524)
				(type default)
			)
			(layer "B.SilkS")
		)
		(fp_line
			(start 1.524 0.762)
			(end 1.524 -0.762)
			(stroke
				(width 0.1524)
				(type default)
			)
			(layer "B.SilkS")
		)
		(fp_line
			(start -1.524 -0.762)
			(end -1.524 0.762)
			(stroke
				(width 0.1524)
				(type default)
			)
			(layer "B.SilkS")
		)
		(fp_line
			(start 1.524 -0.762)
			(end -1.524 -0.762)
			(stroke
				(width 0.1524)
				(type default)
			)
			(layer "B.SilkS")
		)
		(fp_line
			(start -1.1049 0.724916)
			(end -1.1049 -0.724916)
			(stroke
				(width 0.1)
				(type default)
			)
			(layer "B.Fab")
		)
		(fp_line
			(start 1.1049 0.724916)
			(end -1.1049 0.724916)
			(stroke
				(width 0.1)
				(type default)
			)
			(layer "B.Fab")
		)
		(fp_line
			(start -1.1049 -0.724916)
			(end 1.1049 -0.724916)
			(stroke
				(width 0.1)
				(type default)
			)
			(layer "B.Fab")
		)
		(fp_line
			(start 1.1049 -0.724916)
			(end 1.1049 0.724916)
			(stroke
				(width 0.1)
				(type default)
			)
			(layer "B.Fab")
		)
		(pad "1" smd rect
			(at 0.889 0 270)
			(size 1.016 1.27)
			(layers "B.Cu" "B.Mask" "B.Paste")
			(net "SW_P12V_AUX_PVDDCR_CPU0_P0_FLT")
		)
		(pad "2" smd rect
			(at -0.889 0 270)
			(size 1.016 1.27)
			(layers "B.Cu" "B.Mask" "B.Paste")
			(net "GND")
		)
	)
	(footprint ""
		(layer "B.Cu")
		(at 78.072488 -381.238252)
		(property "Reference" "C7025"
			(at 0 0 0)
			(layer "B.SilkS")
			(hide yes)
			(effects
				(font
					(size 1.27 1.27)
				)
				(justify mirror)
			)
		)
		(property "Value" ""
			(at 0 0 0)
			(layer "B.Fab")
			(effects
				(font
					(size 1.27 1.27)
				)
				(justify mirror)
			)
		)
		(duplicate_pad_numbers_are_jumpers no)
		(fp_line
			(start -1.524 -0.762)
			(end -1.524 0.762)
			(stroke
				(width 0.1524)
				(type default)
			)
			(layer "B.SilkS")
		)
		(fp_line
			(start -1.524 0.762)
			(end 1.524 0.762)
			(stroke
				(width 0.1524)
				(type default)
			)
			(layer "B.SilkS")
		)
		(fp_line
			(start 1.524 -0.762)
			(end -1.524 -0.762)
			(stroke
				(width 0.1524)
				(type default)
			)
			(layer "B.SilkS")
		)
		(fp_line
			(start 1.524 0.762)
			(end 1.524 -0.762)
			(stroke
				(width 0.1524)
				(type default)
			)
			(layer "B.SilkS")
		)
		(fp_line
			(start -1.1049 -0.724916)
			(end 1.1049 -0.724916)
			(stroke
				(width 0.1)
				(type default)
			)
			(layer "B.Fab")
		)
		(fp_line
			(start -1.1049 0.724916)
			(end -1.1049 -0.724916)
			(stroke
				(width 0.1)
				(type default)
			)
			(layer "B.Fab")
		)
		(fp_line
			(start 1.1049 -0.724916)
			(end 1.1049 0.724916)
			(stroke
				(width 0.1)
				(type default)
			)
			(layer "B.Fab")
		)
		(fp_line
			(start 1.1049 0.724916)
			(end -1.1049 0.724916)
			(stroke
				(width 0.1)
				(type default)
			)
			(layer "B.Fab")
		)
		(pad "1" smd rect
			(at 0.889 0)
			(size 1.016 1.27)
			(layers "B.Cu" "B.Mask" "B.Paste")
			(net "P0V9_CPU1_RT1_2A")
		)
		(pad "2" smd rect
			(at -0.889 0)
			(size 1.016 1.27)
			(layers "B.Cu" "B.Mask" "B.Paste")
			(net "GND")
		)
	)
	(footprint ""
		(layer "B.Cu")
		(at 398.563592 -341.172292 90)
		(property "Reference" "R934"
			(at 0 0 90)
			(layer "B.SilkS")
			(hide yes)
			(effects
				(font
					(size 1.27 1.27)
				)
				(justify mirror)
			)
		)
		(property "Value" ""
			(at 0 0 90)
			(layer "B.Fab")
			(effects
				(font
					(size 1.27 1.27)
				)
				(justify mirror)
			)
		)
		(duplicate_pad_numbers_are_jumpers no)
		(fp_line
			(start 0.7874 -0.4064)
			(end -0.7874 -0.4064)
			(stroke
				(width 0.1524)
				(type default)
			)
			(layer "B.SilkS")
		)
		(fp_line
			(start -0.7874 -0.4064)
			(end -0.7874 0.4064)
			(stroke
				(width 0.1524)
				(type default)
			)
			(layer "B.SilkS")
		)
		(fp_line
			(start 0.7874 0.4064)
			(end 0.7874 -0.4064)
			(stroke
				(width 0.1524)
				(type default)
			)
			(layer "B.SilkS")
		)
		(fp_line
			(start -0.7874 0.4064)
			(end 0.7874 0.4064)
			(stroke
				(width 0.1524)
				(type default)
			)
			(layer "B.SilkS")
		)
		(fp_line
			(start 0.67945 -0.305054)
			(end 0.12065 -0.305054)
			(stroke
				(width 0.1)
				(type default)
			)
			(layer "B.Fab")
		)
		(fp_line
			(start 0.12065 -0.305054)
			(end 0.12065 -0.2794)
			(stroke
				(width 0.1)
				(type default)
			)
			(layer "B.Fab")
		)
		(fp_line
			(start -0.12065 -0.3048)
			(end -0.67945 -0.3048)
			(stroke
				(width 0.1)
				(type default)
			)
			(layer "B.Fab")
		)
		(fp_line
			(start -0.67945 -0.3048)
			(end -0.67945 0.3048)
			(stroke
				(width 0.1)
				(type default)
			)
			(layer "B.Fab")
		)
		(fp_line
			(start 0.12065 -0.2794)
			(end -0.12065 -0.2794)
			(stroke
				(width 0.1)
				(type default)
			)
			(layer "B.Fab")
		)
		(fp_line
			(start -0.12065 -0.2794)
			(end -0.12065 -0.3048)
			(stroke
				(width 0.1)
				(type default)
			)
			(layer "B.Fab")
		)
		(fp_line
			(start 0.12065 0.2794)
			(end 0.12065 0.3048)
			(stroke
				(width 0.1)
				(type default)
			)
			(layer "B.Fab")
		)
		(fp_line
			(start -0.120396 0.2794)
			(end 0.12065 0.2794)
			(stroke
				(width 0.1)
				(type default)
			)
			(layer "B.Fab")
		)
		(fp_line
			(start 0.67945 0.3048)
			(end 0.67945 -0.305054)
			(stroke
				(width 0.1)
				(type default)
			)
			(layer "B.Fab")
		)
		(fp_line
			(start 0.12065 0.3048)
			(end 0.67945 0.3048)
			(stroke
				(width 0.1)
				(type default)
			)
			(layer "B.Fab")
		)
		(fp_line
			(start -0.120396 0.3048)
			(end -0.120396 0.2794)
			(stroke
				(width 0.1)
				(type default)
			)
			(layer "B.Fab")
		)
		(fp_line
			(start -0.67945 0.3048)
			(end -0.120396 0.3048)
			(stroke
				(width 0.1)
				(type default)
			)
			(layer "B.Fab")
		)
		(pad "1" smd circle
			(at 0.40005 0 270)
			(size 0 0)
			(layers "B.Cu" "B.Mask" "B.Paste")
			(net "FM_BIOS_POST_CMPLT_N")
		)
		(pad "2" smd circle
			(at -0.40005 0 270)
			(size 0 0)
			(layers "B.Cu" "B.Mask" "B.Paste")
			(net "BOOT_RDY_R1_N")
		)
	)
)
